# S9S_MB_2U (Grand Teton) — schematic netlist excerpt (pin names and nets, part order shuffled) for the footprints in the layout excerpt that follows; sources: Cadence DE-HDL packaged netlist, KiCad conversion of 03242023_DA0F0TMBIJ0_F0T_Motherboard_J_brd_V01_OCP.brd

R1595  Q_RES  33.2 1% CHIP  pkg 0402LF  page 155 : A = OCP_SFF_PWRBRK_BUFF_N ; B = OCP_SFF_PWRBRK_N
PC2190  Q_CAP  0.01UF 50V 10% X7R  pkg C0402  page 301 : A = HSC_VOSEN ; B = AGND_HSC
C215  Q_CAP  47UF 4V 20% X6S  pkg C0805  page 74 : A = PVCCIN_CPU0 ; B = GND

(kicad_pcb
	(version 20260206)
	(generator "pcbnew")
	(generator_version "10.0")
	(general
		(thickness 1.6)
		(legacy_teardrops no)
	)
	(paper "A4")
	(title_block
		(title "03242023_DA0F0TMBIJ0_F0T_Motherboard_J_brd_V01_OCP.brd")
		(comment 1 "Grand Teton / footprints 2987-2989 of 6105")
	)
	(layers
		(0 "F.Cu" signal "TOP")
		(4 "In1.Cu" signal "GND")
		(6 "In2.Cu" signal "IN1")
		(8 "In3.Cu" signal "GND1")
		(10 "In4.Cu" signal "IN2")
		(12 "In5.Cu" signal "GND2")
		(14 "In6.Cu" signal "IN3")
		(16 "In7.Cu" signal "GND3")
		(18 "In8.Cu" signal "VCC")
		(20 "In9.Cu" signal "VCC1")
		(22 "In10.Cu" signal "GND4")
		(24 "In11.Cu" signal "IN4")
		(26 "In12.Cu" signal "GND5")
		(28 "In13.Cu" signal "IN5")
		(30 "In14.Cu" signal "GND6")
		(32 "In15.Cu" signal "IN6")
		(34 "In16.Cu" signal "GND7")
		(2 "B.Cu" signal "BOTTOM")
		(9 "F.Adhes" user "F.Adhesive")
		(11 "B.Adhes" user "B.Adhesive")
		(13 "F.Paste" user "Package Geometry/Pastemask Top")
		(15 "B.Paste" user "Package Geometry/Pastemask Bottom")
		(5 "F.SilkS" user "Ref Des/Silkscreen Top")
		(7 "B.SilkS" user "Ref Des/Silkscreen Bottom")
		(1 "F.Mask" user "Board Geometry/Soldermask Top")
		(3 "B.Mask" user "Board Geometry/Soldermask Bottom")
		(17 "Dwgs.User" user "User.Drawings")
		(19 "Cmts.User" user "User.Comments")
		(21 "Eco1.User" user "User.Eco1")
		(23 "Eco2.User" user "User.Eco2")
		(25 "Edge.Cuts" user "Board Geometry/Outline")
		(27 "Margin" user)
		(31 "F.CrtYd" user "Package Geometry/Place Bound Top")
		(29 "B.CrtYd" user "Package Geometry/Place Bound Bottom")
		(35 "F.Fab" user "Ref Des/Assembly Top")
		(33 "B.Fab" user "Ref Des/Assembly Bottom")
	)
	(footprint ""
		(layer "F.Cu")
		(at 393.115038 -31.185612 90)
		(property "Reference" "R1595"
			(at 0 0 90)
			(layer "F.SilkS")
			(hide yes)
			(effects
				(font
					(size 1.27 1.27)
				)
			)
		)
		(property "Value" ""
			(at 0 0 90)
			(layer "F.Fab")
			(effects
				(font
					(size 1.27 1.27)
				)
			)
		)
		(duplicate_pad_numbers_are_jumpers no)
		(fp_line
			(start 0.7874 -0.4064)
			(end 0.7874 0.4064)
			(stroke
				(width 0.1524)
				(type default)
			)
			(layer "F.SilkS")
		)
		(fp_line
			(start -0.7874 -0.4064)
			(end 0.7874 -0.4064)
			(stroke
				(width 0.1524)
				(type default)
			)
			(layer "F.SilkS")
		)
		(fp_line
			(start 0.7874 0.4064)
			(end -0.7874 0.4064)
			(stroke
				(width 0.1524)
				(type default)
			)
			(layer "F.SilkS")
		)
		(fp_line
			(start -0.7874 0.4064)
			(end -0.7874 -0.4064)
			(stroke
				(width 0.1524)
				(type default)
			)
			(layer "F.SilkS")
		)
		(fp_line
			(start -0.12065 -0.305054)
			(end -0.12065 -0.2794)
			(stroke
				(width 0.1)
				(type default)
			)
			(layer "F.Fab")
		)
		(fp_line
			(start -0.67945 -0.305054)
			(end -0.12065 -0.305054)
			(stroke
				(width 0.1)
				(type default)
			)
			(layer "F.Fab")
		)
		(fp_line
			(start 0.67945 -0.3048)
			(end 0.67945 0.3048)
			(stroke
				(width 0.1)
				(type default)
			)
			(layer "F.Fab")
		)
		(fp_line
			(start 0.12065 -0.3048)
			(end 0.67945 -0.3048)
			(stroke
				(width 0.1)
				(type default)
			)
			(layer "F.Fab")
		)
		(fp_line
			(start 0.12065 -0.2794)
			(end 0.12065 -0.3048)
			(stroke
				(width 0.1)
				(type default)
			)
			(layer "F.Fab")
		)
		(fp_line
			(start -0.12065 -0.2794)
			(end 0.12065 -0.2794)
			(stroke
				(width 0.1)
				(type default)
			)
			(layer "F.Fab")
		)
		(fp_line
			(start 0.120396 0.2794)
			(end -0.12065 0.2794)
			(stroke
				(width 0.1)
				(type default)
			)
			(layer "F.Fab")
		)
		(fp_line
			(start -0.12065 0.2794)
			(end -0.12065 0.3048)
			(stroke
				(width 0.1)
				(type default)
			)
			(layer "F.Fab")
		)
		(fp_line
			(start 0.67945 0.3048)
			(end 0.120396 0.3048)
			(stroke
				(width 0.1)
				(type default)
			)
			(layer "F.Fab")
		)
		(fp_line
			(start 0.120396 0.3048)
			(end 0.120396 0.2794)
			(stroke
				(width 0.1)
				(type default)
			)
			(layer "F.Fab")
		)
		(fp_line
			(start -0.12065 0.3048)
			(end -0.67945 0.3048)
			(stroke
				(width 0.1)
				(type default)
			)
			(layer "F.Fab")
		)
		(fp_line
			(start -0.67945 0.3048)
			(end -0.67945 -0.305054)
			(stroke
				(width 0.1)
				(type default)
			)
			(layer "F.Fab")
		)
		(pad "1" smd circle
			(at -0.40005 0 90)
			(size 0 0)
			(layers "F.Cu" "F.Mask" "F.Paste")
			(net "OCP_SFF_PWRBRK_BUFF_N")
		)
		(pad "2" smd circle
			(at 0.40005 0 90)
			(size 0 0)
			(layers "F.Cu" "F.Mask" "F.Paste")
			(net "OCP_SFF_PWRBRK_N")
		)
	)
	(footprint ""
		(layer "F.Cu")
		(at 359.71988 -294.01008 180)
		(property "Reference" "C215"
			(at 0 0 180)
			(layer "F.SilkS")
			(hide yes)
			(effects
				(font
					(size 1.27 1.27)
				)
			)
		)
		(property "Value" ""
			(at 0 0 180)
			(layer "F.Fab")
			(effects
				(font
					(size 1.27 1.27)
				)
			)
		)
		(duplicate_pad_numbers_are_jumpers no)
		(fp_line
			(start 1.524 0.762)
			(end -1.524 0.762)
			(stroke
				(width 0.1524)
				(type default)
			)
			(layer "F.SilkS")
		)
		(fp_line
			(start 1.524 -0.762)
			(end 1.524 0.762)
			(stroke
				(width 0.1524)
				(type default)
			)
			(layer "F.SilkS")
		)
		(fp_line
			(start -1.524 0.762)
			(end -1.524 -0.762)
			(stroke
				(width 0.1524)
				(type default)
			)
			(layer "F.SilkS")
		)
		(fp_line
			(start -1.524 -0.762)
			(end 1.524 -0.762)
			(stroke
				(width 0.1524)
				(type default)
			)
			(layer "F.SilkS")
		)
		(fp_line
			(start 1.1049 0.724916)
			(end 1.1049 -0.724916)
			(stroke
				(width 0.1)
				(type default)
			)
			(layer "F.Fab")
		)
		(fp_line
			(start 1.1049 -0.724916)
			(end -1.1049 -0.724916)
			(stroke
				(width 0.1)
				(type default)
			)
			(layer "F.Fab")
		)
		(fp_line
			(start -1.1049 0.724916)
			(end 1.1049 0.724916)
			(stroke
				(width 0.1)
				(type default)
			)
			(layer "F.Fab")
		)
		(fp_line
			(start -1.1049 -0.724916)
			(end -1.1049 0.724916)
			(stroke
				(width 0.1)
				(type default)
			)
			(layer "F.Fab")
		)
		(pad "1" smd rect
			(at -0.889 0)
			(size 1.016 1.27)
			(layers "F.Cu" "F.Mask" "F.Paste")
			(net "PVCCIN_CPU0")
		)
		(pad "2" smd rect
			(at 0.889 0)
			(size 1.016 1.27)
			(layers "F.Cu" "F.Mask" "F.Paste")
			(net "GND")
		)
	)
	(footprint ""
		(layer "F.Cu")
		(at 183.198008 -398.651222 180)
		(property "Reference" "PC2190"
			(at 0 0 180)
			(layer "F.SilkS")
			(hide yes)
			(effects
				(font
					(size 1.27 1.27)
				)
			)
		)
		(property "Value" ""
			(at 0 0 180)
			(layer "F.Fab")
			(effects
				(font
					(size 1.27 1.27)
				)
			)
		)
		(duplicate_pad_numbers_are_jumpers no)
		(fp_line
			(start 0.7874 0.4064)
			(end -0.7874 0.4064)
			(stroke
				(width 0.1524)
				(type default)
			)
			(layer "F.SilkS")
		)
		(fp_line
			(start 0.7874 -0.4064)
			(end 0.7874 0.4064)
			(stroke
				(width 0.1524)
				(type default)
			)
			(layer "F.SilkS")
		)
		(fp_line
			(start -0.7874 0.4064)
			(end -0.7874 -0.4064)
			(stroke
				(width 0.1524)
				(type default)
			)
			(layer "F.SilkS")
		)
		(fp_line
			(start -0.7874 -0.4064)
			(end 0.7874 -0.4064)
			(stroke
				(width 0.1524)
				(type default)
			)
			(layer "F.SilkS")
		)
		(fp_line
			(start 0.67945 0.3048)
			(end 0.120396 0.3048)
			(stroke
				(width 0.1)
				(type default)
			)
			(layer "F.Fab")
		)
		(fp_line
			(start 0.67945 -0.3048)
			(end 0.67945 0.3048)
			(stroke
				(width 0.1)
				(type default)
			)
			(layer "F.Fab")
		)
		(fp_line
			(start 0.12065 -0.2794)
			(end 0.12065 -0.3048)
			(stroke
				(width 0.1)
				(type default)
			)
			(layer "F.Fab")
		)
		(fp_line
			(start 0.12065 -0.3048)
			(end 0.67945 -0.3048)
			(stroke
				(width 0.1)
				(type default)
			)
			(layer "F.Fab")
		)
		(fp_line
			(start 0.120396 0.3048)
			(end 0.120396 0.2794)
			(stroke
				(width 0.1)
				(type default)
			)
			(layer "F.Fab")
		)
		(fp_line
			(start 0.120396 0.2794)
			(end -0.12065 0.2794)
			(stroke
				(width 0.1)
				(type default)
			)
			(layer "F.Fab")
		)
		(fp_line
			(start -0.12065 0.3048)
			(end -0.67945 0.3048)
			(stroke
				(width 0.1)
				(type default)
			)
			(layer "F.Fab")
		)
		(fp_line
			(start -0.12065 0.2794)
			(end -0.12065 0.3048)
			(stroke
				(width 0.1)
				(type default)
			)
			(layer "F.Fab")
		)
		(fp_line
			(start -0.12065 -0.2794)
			(end 0.12065 -0.2794)
			(stroke
				(width 0.1)
				(type default)
			)
			(layer "F.Fab")
		)
		(fp_line
			(start -0.12065 -0.305054)
			(end -0.12065 -0.2794)
			(stroke
				(width 0.1)
				(type default)
			)
			(layer "F.Fab")
		)
		(fp_line
			(start -0.67945 0.3048)
			(end -0.67945 -0.305054)
			(stroke
				(width 0.1)
				(type default)
			)
			(layer "F.Fab")
		)
		(fp_line
			(start -0.67945 -0.305054)
			(end -0.12065 -0.305054)
			(stroke
				(width 0.1)
				(type default)
			)
			(layer "F.Fab")
		)
		(pad "1" smd circle
			(at -0.40005 0 180)
			(size 0 0)
			(layers "F.Cu" "F.Mask" "F.Paste")
			(net "HSC_VOSEN")
		)
		(pad "2" smd circle
			(at 0.40005 0 180)
			(size 0 0)
			(layers "F.Cu" "F.Mask" "F.Paste")
			(net "AGND_HSC")
		)
	)
)
